FILE_TYPE = MACRO_DRAWING;
SET COLOR_WIRE YELLOW;
SET COLOR_PROP ORANGE;
SET COLOR_DOT WHITE;
SET COLOR_ARC YELLOW;
SET COLOR_BODY GREEN;
SET COLOR_NOTE PURPLE;
SET PROP_DISPLAY VALUE;
SET PAGE_NUMBER P157;
FORCEADD QUANTA_TITLE_BLOCK_C..1
(0 0);
FORCEPROP 1 LAST CUSTOM_TXT_CDS <NAME_2>
J 0
(-3175 50);
FORCEPROP 1 LAST CUSTOM_TXT_CDS <NAME_1>
J 0
(-3175 175);
FORCEPROP 1 LAST CUSTOM_TXT_CDS <Q_NUMBER>
J 0
(-1403 103);
DISPLAY 1.212766 (-1403 103);
FORCEPROP 1 LAST CUSTOM_TXT_CDS <Q_PROJ>
J 0
(-2382 102);
DISPLAY 1.212766 (-2382 102);
FORCEPROP 1 LAST CUSTOM_TXT_CDS <Q_REV>
J 0
(-184 103);
DISPLAY 1.212766 (-184 103);
FORCEPROP 1 LAST CUSTOM_TXT_CDS <CON_LAST_MODIFIED>
J 0
(-1885 15);
DISPLAY 0.978723 (-1885 15);
FORCEPROP 1 LAST CUSTOM_TXT_CDS <CON_PAGE_NUM> OF <CON_TOTAL_PAGES>
J 0
(-446 18);
DISPLAY 0.978723 (-446 18);
FORCEPROP 1 LAST Q_TITLE P12V PWR CONN
J 0
(-9250 100);
DISPLAY 2.446809 (-9250 100);
PAINT GREEN (-9250 100);
FORCEPROP 1 LAST Q_DEPT BU9
J 1
(-3763 49);
DISPLAY 1.957447 (-3763 49);
PAINT GREEN (-3763 49);
FORCEPROP 2 LAST PAGE_BORDER TRUE
J 0
(-7890 5250);
DISPLAY 0.638298 (-7890 5250);
PAINT PINK (-7890 5250);
DISPLAY INVISIBLE (-7890 5250);
FORCEPROP 2 LAST CDS_LIB pure_quanta
J 0
(0 0);
DISPLAY INVISIBLE (0 0);
FORCEPROP 1 LAST CDS_LMAN_SYM_OUTLINE -9475,6775,100,-125
J 0
(0 0);
DISPLAY 0.468085 (0 0);
PAINT GREEN (0 0);
DISPLAY INVISIBLE (0 0);
FORCEPROP 1 LAST COMMENT_BODY TRUE
J 0
(12 -13);
DISPLAY 0.978723 (12 -13);
PAINT GREEN (12 -13);
DISPLAY INVISIBLE (12 -13);
FORCEPROP 2 LAST CDS_XR_PAGE_TITLE CR-157 : @T6G_MB_LIB.T6G(SCH_1):PAGE157
J 0
(-7890 5250);
DISPLAY 0.638298 (-7890 5250);
PAINT PINK (-7890 5250);
DISPLAY INVISIBLE (-7890 5250);
FORCEPROP 2 LAST CUSTOM_TXT_CDS <XR_PAGE_TITLE>
J 0
(-7890 5250);
DISPLAY 0.638298 (-7890 5250);
PAINT PINK (-7890 5250);
DISPLAY INVISIBLE (-7890 5250);
FORCEPROP 0 LAST CDS_CON_LAST_MODIFIED Wed Mar 09 20:29:49 2022
J 0
(-1885 15);
DISPLAY INVISIBLE (-1885 15);
QUIT
